(kicad_pcb
	(version 20260206)
	(generator "pcbnew")
	(generator_version "10.0")
	(general
		(thickness 1.6)
		(legacy_teardrops no)
	)
	(paper "A4")
	(title_block
		(title "12092022_DA0F0TFB6D0_F0T_FAN_BOARD_MP5048_D_brd_v02_OCP.brd")
		(comment 1 "Grand Teton / footprints 464-470 of 924")
	)
	(layers
		(0 "F.Cu" signal "TOP")
		(4 "In1.Cu" signal "GND")
		(6 "In2.Cu" signal "IN1")
		(8 "In3.Cu" signal "IN2")
		(10 "In4.Cu" signal "GND1")
		(2 "B.Cu" signal "BOTTOM")
		(9 "F.Adhes" user "F.Adhesive")
		(11 "B.Adhes" user "B.Adhesive")
		(13 "F.Paste" user "Package Geometry/Pastemask Top")
		(15 "B.Paste" user "Package Geometry/Pastemask Bottom")
		(5 "F.SilkS" user "Ref Des/Silkscreen Top")
		(7 "B.SilkS" user "Ref Des/Silkscreen Bottom")
		(1 "F.Mask" user "Board Geometry/Soldermask Top")
		(3 "B.Mask" user "Board Geometry/Soldermask Bottom")
		(17 "Dwgs.User" user "User.Drawings")
		(19 "Cmts.User" user "User.Comments")
		(21 "Eco1.User" user "User.Eco1")
		(23 "Eco2.User" user "User.Eco2")
		(25 "Edge.Cuts" user "Board Geometry/Outline")
		(27 "Margin" user)
		(31 "F.CrtYd" user "Package Geometry/Place Bound Top")
		(29 "B.CrtYd" user "Package Geometry/Place Bound Bottom")
		(35 "F.Fab" user "Ref Des/Assembly Top")
		(33 "B.Fab" user "Ref Des/Assembly Bottom")
	)
	(footprint ""
		(layer "F.Cu")
		(at 28.321 -33.401)
		(property "Reference" "U408"
			(at 0.508 2.18567 0)
			(unlocked yes)
			(layer "F.SilkS")
			(effects
				(font
					(size 0.7874 0.5842)
					(thickness 0.1524)
				)
				(justify left)
			)
		)
		(property "Value" ""
			(at 0 0 0)
			(layer "F.Fab")
			(effects
				(font
					(size 1.27 1.27)
				)
			)
		)
		(duplicate_pad_numbers_are_jumpers no)
		(fp_line
			(start -1.335278 -1.100074)
			(end -1.335278 1.100074)
			(stroke
				(width 0.1524)
				(type default)
			)
			(layer "F.SilkS")
		)
		(fp_line
			(start -1.335278 1.100074)
			(end 1.335278 1.100074)
			(stroke
				(width 0.1524)
				(type default)
			)
			(layer "F.SilkS")
		)
		(fp_line
			(start 1.335278 -1.100074)
			(end -1.335278 -1.100074)
			(stroke
				(width 0.1524)
				(type default)
			)
			(layer "F.SilkS")
		)
		(fp_line
			(start 1.335278 1.100074)
			(end 1.335278 -1.100074)
			(stroke
				(width 0.1524)
				(type default)
			)
			(layer "F.SilkS")
		)
		(fp_line
			(start -0.674878 -1.100074)
			(end -0.674878 1.100074)
			(stroke
				(width 0.1)
				(type default)
			)
			(layer "F.Fab")
		)
		(fp_line
			(start -0.674878 1.100074)
			(end 0.674878 1.100074)
			(stroke
				(width 0.1)
				(type default)
			)
			(layer "F.Fab")
		)
		(fp_line
			(start 0.674878 -1.100074)
			(end -0.674878 -1.100074)
			(stroke
				(width 0.1)
				(type default)
			)
			(layer "F.Fab")
		)
		(fp_line
			(start 0.674878 1.100074)
			(end 0.674878 -1.100074)
			(stroke
				(width 0.1)
				(type default)
			)
			(layer "F.Fab")
		)
		(pad "D" smd rect
			(at 0.8001 0 270)
			(size 0.6096 0.8128)
			(layers "F.Cu" "F.Mask" "F.Paste")
			(net "U408_D1")
		)
		(pad "G" smd rect
			(at -0.8001 -0.649986 270)
			(size 0.6096 0.8128)
			(layers "F.Cu" "F.Mask" "F.Paste")
			(net "FAN_3_PRESENT")
		)
		(pad "S" smd rect
			(at -0.8001 0.649986 270)
			(size 0.6096 0.8128)
			(layers "F.Cu" "F.Mask" "F.Paste")
			(net "GND")
		)
	)
	(footprint ""
		(layer "F.Cu")
		(at 3.7338 -35.821874 90)
		(property "Reference" "C157"
			(at 0 0 90)
			(layer "F.SilkS")
			(hide yes)
			(effects
				(font
					(size 1.27 1.27)
				)
			)
		)
		(property "Value" ""
			(at 0 0 90)
			(layer "F.Fab")
			(effects
				(font
					(size 1.27 1.27)
				)
			)
		)
		(duplicate_pad_numbers_are_jumpers no)
		(fp_line
			(start 1.524 -0.762)
			(end 1.524 0.762)
			(stroke
				(width 0.1524)
				(type default)
			)
			(layer "F.SilkS")
		)
		(fp_line
			(start -1.524 -0.762)
			(end 1.524 -0.762)
			(stroke
				(width 0.1524)
				(type default)
			)
			(layer "F.SilkS")
		)
		(fp_line
			(start 1.524 0.762)
			(end -1.524 0.762)
			(stroke
				(width 0.1524)
				(type default)
			)
			(layer "F.SilkS")
		)
		(fp_line
			(start -1.524 0.762)
			(end -1.524 -0.762)
			(stroke
				(width 0.1524)
				(type default)
			)
			(layer "F.SilkS")
		)
		(fp_line
			(start 1.1049 -0.724916)
			(end -1.1049 -0.724916)
			(stroke
				(width 0.1)
				(type default)
			)
			(layer "F.Fab")
		)
		(fp_line
			(start -1.1049 -0.724916)
			(end -1.1049 0.724916)
			(stroke
				(width 0.1)
				(type default)
			)
			(layer "F.Fab")
		)
		(fp_line
			(start 1.1049 0.724916)
			(end 1.1049 -0.724916)
			(stroke
				(width 0.1)
				(type default)
			)
			(layer "F.Fab")
		)
		(fp_line
			(start -1.1049 0.724916)
			(end 1.1049 0.724916)
			(stroke
				(width 0.1)
				(type default)
			)
			(layer "F.Fab")
		)
		(pad "1" smd rect
			(at -0.889 0 270)
			(size 1.016 1.27)
			(layers "F.Cu" "F.Mask" "F.Paste")
			(net "P12V_LED_FAN4")
		)
		(pad "2" smd rect
			(at 0.889 0 270)
			(size 1.016 1.27)
			(layers "F.Cu" "F.Mask" "F.Paste")
			(net "GND")
		)
	)
	(footprint ""
		(layer "F.Cu")
		(at 37.338 -114.738912 180)
		(property "Reference" "R5220"
			(at 0 0 180)
			(layer "F.SilkS")
			(hide yes)
			(effects
				(font
					(size 1.27 1.27)
				)
			)
		)
		(property "Value" ""
			(at 0 0 180)
			(layer "F.Fab")
			(effects
				(font
					(size 1.27 1.27)
				)
			)
		)
		(duplicate_pad_numbers_are_jumpers no)
		(fp_line
			(start 0.7874 0.4064)
			(end -0.7874 0.4064)
			(stroke
				(width 0.1524)
				(type default)
			)
			(layer "F.SilkS")
		)
		(fp_line
			(start 0.7874 -0.4064)
			(end 0.7874 0.4064)
			(stroke
				(width 0.1524)
				(type default)
			)
			(layer "F.SilkS")
		)
		(fp_line
			(start -0.7874 0.4064)
			(end -0.7874 -0.4064)
			(stroke
				(width 0.1524)
				(type default)
			)
			(layer "F.SilkS")
		)
		(fp_line
			(start -0.7874 -0.4064)
			(end 0.7874 -0.4064)
			(stroke
				(width 0.1524)
				(type default)
			)
			(layer "F.SilkS")
		)
		(fp_line
			(start 0.67945 0.3048)
			(end 0.120396 0.3048)
			(stroke
				(width 0.1)
				(type default)
			)
			(layer "F.Fab")
		)
		(fp_line
			(start 0.67945 -0.3048)
			(end 0.67945 0.3048)
			(stroke
				(width 0.1)
				(type default)
			)
			(layer "F.Fab")
		)
		(fp_line
			(start 0.12065 -0.2794)
			(end 0.12065 -0.3048)
			(stroke
				(width 0.1)
				(type default)
			)
			(layer "F.Fab")
		)
		(fp_line
			(start 0.12065 -0.3048)
			(end 0.67945 -0.3048)
			(stroke
				(width 0.1)
				(type default)
			)
			(layer "F.Fab")
		)
		(fp_line
			(start 0.120396 0.3048)
			(end 0.120396 0.2794)
			(stroke
				(width 0.1)
				(type default)
			)
			(layer "F.Fab")
		)
		(fp_line
			(start 0.120396 0.2794)
			(end -0.12065 0.2794)
			(stroke
				(width 0.1)
				(type default)
			)
			(layer "F.Fab")
		)
		(fp_line
			(start -0.12065 0.3048)
			(end -0.67945 0.3048)
			(stroke
				(width 0.1)
				(type default)
			)
			(layer "F.Fab")
		)
		(fp_line
			(start -0.12065 0.2794)
			(end -0.12065 0.3048)
			(stroke
				(width 0.1)
				(type default)
			)
			(layer "F.Fab")
		)
		(fp_line
			(start -0.12065 -0.2794)
			(end 0.12065 -0.2794)
			(stroke
				(width 0.1)
				(type default)
			)
			(layer "F.Fab")
		)
		(fp_line
			(start -0.12065 -0.305054)
			(end -0.12065 -0.2794)
			(stroke
				(width 0.1)
				(type default)
			)
			(layer "F.Fab")
		)
		(fp_line
			(start -0.67945 0.3048)
			(end -0.67945 -0.305054)
			(stroke
				(width 0.1)
				(type default)
			)
			(layer "F.Fab")
		)
		(fp_line
			(start -0.67945 -0.305054)
			(end -0.12065 -0.305054)
			(stroke
				(width 0.1)
				(type default)
			)
			(layer "F.Fab")
		)
		(pad "1" smd circle
			(at -0.40005 0 180)
			(size 0 0)
			(layers "F.Cu" "F.Mask" "F.Paste")
			(net "FAN_2_PWM_IL_R")
		)
		(pad "2" smd circle
			(at 0.40005 0 180)
			(size 0 0)
			(layers "F.Cu" "F.Mask" "F.Paste")
			(net "FAN_2_PWM_IL")
		)
	)
	(footprint ""
		(layer "F.Cu")
		(at 6.477 -172.847)
		(property "Reference" "R4860"
			(at 0 0 0)
			(layer "F.SilkS")
			(hide yes)
			(effects
				(font
					(size 1.27 1.27)
				)
			)
		)
		(property "Value" ""
			(at 0 0 0)
			(layer "F.Fab")
			(effects
				(font
					(size 1.27 1.27)
				)
			)
		)
		(duplicate_pad_numbers_are_jumpers no)
		(fp_line
			(start -0.7874 -0.4064)
			(end 0.7874 -0.4064)
			(stroke
				(width 0.1524)
				(type default)
			)
			(layer "F.SilkS")
		)
		(fp_line
			(start -0.7874 0.4064)
			(end -0.7874 -0.4064)
			(stroke
				(width 0.1524)
				(type default)
			)
			(layer "F.SilkS")
		)
		(fp_line
			(start 0.7874 -0.4064)
			(end 0.7874 0.4064)
			(stroke
				(width 0.1524)
				(type default)
			)
			(layer "F.SilkS")
		)
		(fp_line
			(start 0.7874 0.4064)
			(end -0.7874 0.4064)
			(stroke
				(width 0.1524)
				(type default)
			)
			(layer "F.SilkS")
		)
		(fp_line
			(start -0.67945 -0.305054)
			(end -0.12065 -0.305054)
			(stroke
				(width 0.1)
				(type default)
			)
			(layer "F.Fab")
		)
		(fp_line
			(start -0.67945 0.3048)
			(end -0.67945 -0.305054)
			(stroke
				(width 0.1)
				(type default)
			)
			(layer "F.Fab")
		)
		(fp_line
			(start -0.12065 -0.305054)
			(end -0.12065 -0.2794)
			(stroke
				(width 0.1)
				(type default)
			)
			(layer "F.Fab")
		)
		(fp_line
			(start -0.12065 -0.2794)
			(end 0.12065 -0.2794)
			(stroke
				(width 0.1)
				(type default)
			)
			(layer "F.Fab")
		)
		(fp_line
			(start -0.12065 0.2794)
			(end -0.12065 0.3048)
			(stroke
				(width 0.1)
				(type default)
			)
			(layer "F.Fab")
		)
		(fp_line
			(start -0.12065 0.3048)
			(end -0.67945 0.3048)
			(stroke
				(width 0.1)
				(type default)
			)
			(layer "F.Fab")
		)
		(fp_line
			(start 0.120396 0.2794)
			(end -0.12065 0.2794)
			(stroke
				(width 0.1)
				(type default)
			)
			(layer "F.Fab")
		)
		(fp_line
			(start 0.120396 0.3048)
			(end 0.120396 0.2794)
			(stroke
				(width 0.1)
				(type default)
			)
			(layer "F.Fab")
		)
		(fp_line
			(start 0.12065 -0.3048)
			(end 0.67945 -0.3048)
			(stroke
				(width 0.1)
				(type default)
			)
			(layer "F.Fab")
		)
		(fp_line
			(start 0.12065 -0.2794)
			(end 0.12065 -0.3048)
			(stroke
				(width 0.1)
				(type default)
			)
			(layer "F.Fab")
		)
		(fp_line
			(start 0.67945 -0.3048)
			(end 0.67945 0.3048)
			(stroke
				(width 0.1)
				(type default)
			)
			(layer "F.Fab")
		)
		(fp_line
			(start 0.67945 0.3048)
			(end 0.120396 0.3048)
			(stroke
				(width 0.1)
				(type default)
			)
			(layer "F.Fab")
		)
		(pad "1" smd circle
			(at -0.40005 0)
			(size 0 0)
			(layers "F.Cu" "F.Mask" "F.Paste")
			(net "P3V3_AUX")
		)
		(pad "2" smd circle
			(at 0.40005 0)
			(size 0 0)
			(layers "F.Cu" "F.Mask" "F.Paste")
			(net "FAN_6_PRSNT_BUF_R_N")
		)
	)
	(footprint ""
		(layer "F.Cu")
		(at 20.828 -177.8 180)
		(property "Reference" "R5683"
			(at 0 0 180)
			(layer "F.SilkS")
			(hide yes)
			(effects
				(font
					(size 1.27 1.27)
				)
			)
		)
		(property "Value" ""
			(at 0 0 180)
			(layer "F.Fab")
			(effects
				(font
					(size 1.27 1.27)
				)
			)
		)
		(duplicate_pad_numbers_are_jumpers no)
		(fp_line
			(start 0.7874 0.4064)
			(end -0.7874 0.4064)
			(stroke
				(width 0.1524)
				(type default)
			)
			(layer "F.SilkS")
		)
		(fp_line
			(start 0.7874 -0.4064)
			(end 0.7874 0.4064)
			(stroke
				(width 0.1524)
				(type default)
			)
			(layer "F.SilkS")
		)
		(fp_line
			(start -0.7874 0.4064)
			(end -0.7874 -0.4064)
			(stroke
				(width 0.1524)
				(type default)
			)
			(layer "F.SilkS")
		)
		(fp_line
			(start -0.7874 -0.4064)
			(end 0.7874 -0.4064)
			(stroke
				(width 0.1524)
				(type default)
			)
			(layer "F.SilkS")
		)
		(fp_line
			(start 0.67945 0.3048)
			(end 0.120396 0.3048)
			(stroke
				(width 0.1)
				(type default)
			)
			(layer "F.Fab")
		)
		(fp_line
			(start 0.67945 -0.3048)
			(end 0.67945 0.3048)
			(stroke
				(width 0.1)
				(type default)
			)
			(layer "F.Fab")
		)
		(fp_line
			(start 0.12065 -0.2794)
			(end 0.12065 -0.3048)
			(stroke
				(width 0.1)
				(type default)
			)
			(layer "F.Fab")
		)
		(fp_line
			(start 0.12065 -0.3048)
			(end 0.67945 -0.3048)
			(stroke
				(width 0.1)
				(type default)
			)
			(layer "F.Fab")
		)
		(fp_line
			(start 0.120396 0.3048)
			(end 0.120396 0.2794)
			(stroke
				(width 0.1)
				(type default)
			)
			(layer "F.Fab")
		)
		(fp_line
			(start 0.120396 0.2794)
			(end -0.12065 0.2794)
			(stroke
				(width 0.1)
				(type default)
			)
			(layer "F.Fab")
		)
		(fp_line
			(start -0.12065 0.3048)
			(end -0.67945 0.3048)
			(stroke
				(width 0.1)
				(type default)
			)
			(layer "F.Fab")
		)
		(fp_line
			(start -0.12065 0.2794)
			(end -0.12065 0.3048)
			(stroke
				(width 0.1)
				(type default)
			)
			(layer "F.Fab")
		)
		(fp_line
			(start -0.12065 -0.2794)
			(end 0.12065 -0.2794)
			(stroke
				(width 0.1)
				(type default)
			)
			(layer "F.Fab")
		)
		(fp_line
			(start -0.12065 -0.305054)
			(end -0.12065 -0.2794)
			(stroke
				(width 0.1)
				(type default)
			)
			(layer "F.Fab")
		)
		(fp_line
			(start -0.67945 0.3048)
			(end -0.67945 -0.305054)
			(stroke
				(width 0.1)
				(type default)
			)
			(layer "F.Fab")
		)
		(fp_line
			(start -0.67945 -0.305054)
			(end -0.12065 -0.305054)
			(stroke
				(width 0.1)
				(type default)
			)
			(layer "F.Fab")
		)
		(pad "1" smd circle
			(at -0.40005 0 180)
			(size 0 0)
			(layers "F.Cu" "F.Mask" "F.Paste")
			(net "P3V3_AUX")
		)
		(pad "2" smd circle
			(at 0.40005 0 180)
			(size 0 0)
			(layers "F.Cu" "F.Mask" "F.Paste")
			(net "FM_BOARD_ID0")
		)
	)
	(footprint ""
		(layer "F.Cu")
		(at 3.248914 -67.494912 90)
		(property "Reference" "C2060"
			(at 0 0 90)
			(layer "F.SilkS")
			(hide yes)
			(effects
				(font
					(size 1.27 1.27)
				)
			)
		)
		(property "Value" ""
			(at 0 0 90)
			(layer "F.Fab")
			(effects
				(font
					(size 1.27 1.27)
				)
			)
		)
		(duplicate_pad_numbers_are_jumpers no)
		(fp_line
			(start 0.7874 -0.4064)
			(end 0.7874 0.4064)
			(stroke
				(width 0.1524)
				(type default)
			)
			(layer "F.SilkS")
		)
		(fp_line
			(start -0.7874 -0.4064)
			(end 0.7874 -0.4064)
			(stroke
				(width 0.1524)
				(type default)
			)
			(layer "F.SilkS")
		)
		(fp_line
			(start 0.7874 0.4064)
			(end -0.7874 0.4064)
			(stroke
				(width 0.1524)
				(type default)
			)
			(layer "F.SilkS")
		)
		(fp_line
			(start -0.7874 0.4064)
			(end -0.7874 -0.4064)
			(stroke
				(width 0.1524)
				(type default)
			)
			(layer "F.SilkS")
		)
		(fp_line
			(start -0.12065 -0.305054)
			(end -0.12065 -0.2794)
			(stroke
				(width 0.1)
				(type default)
			)
			(layer "F.Fab")
		)
		(fp_line
			(start -0.67945 -0.305054)
			(end -0.12065 -0.305054)
			(stroke
				(width 0.1)
				(type default)
			)
			(layer "F.Fab")
		)
		(fp_line
			(start 0.67945 -0.3048)
			(end 0.67945 0.3048)
			(stroke
				(width 0.1)
				(type default)
			)
			(layer "F.Fab")
		)
		(fp_line
			(start 0.12065 -0.3048)
			(end 0.67945 -0.3048)
			(stroke
				(width 0.1)
				(type default)
			)
			(layer "F.Fab")
		)
		(fp_line
			(start 0.12065 -0.2794)
			(end 0.12065 -0.3048)
			(stroke
				(width 0.1)
				(type default)
			)
			(layer "F.Fab")
		)
		(fp_line
			(start -0.12065 -0.2794)
			(end 0.12065 -0.2794)
			(stroke
				(width 0.1)
				(type default)
			)
			(layer "F.Fab")
		)
		(fp_line
			(start 0.120396 0.2794)
			(end -0.12065 0.2794)
			(stroke
				(width 0.1)
				(type default)
			)
			(layer "F.Fab")
		)
		(fp_line
			(start -0.12065 0.2794)
			(end -0.12065 0.3048)
			(stroke
				(width 0.1)
				(type default)
			)
			(layer "F.Fab")
		)
		(fp_line
			(start 0.67945 0.3048)
			(end 0.120396 0.3048)
			(stroke
				(width 0.1)
				(type default)
			)
			(layer "F.Fab")
		)
		(fp_line
			(start 0.120396 0.3048)
			(end 0.120396 0.2794)
			(stroke
				(width 0.1)
				(type default)
			)
			(layer "F.Fab")
		)
		(fp_line
			(start -0.12065 0.3048)
			(end -0.67945 0.3048)
			(stroke
				(width 0.1)
				(type default)
			)
			(layer "F.Fab")
		)
		(fp_line
			(start -0.67945 0.3048)
			(end -0.67945 -0.305054)
			(stroke
				(width 0.1)
				(type default)
			)
			(layer "F.Fab")
		)
		(pad "1" smd circle
			(at -0.40005 0 90)
			(size 0 0)
			(layers "F.Cu" "F.Mask" "F.Paste")
			(net "P3V3_AUX")
		)
		(pad "2" smd circle
			(at 0.40005 0 90)
			(size 0 0)
			(layers "F.Cu" "F.Mask" "F.Paste")
			(net "GND")
		)
	)
	(footprint ""
		(layer "F.Cu")
		(at 3.937 -308.61)
		(property "Reference" "C2051"
			(at 0 0 0)
			(layer "F.SilkS")
			(hide yes)
			(effects
				(font
					(size 1.27 1.27)
				)
			)
		)
		(property "Value" ""
			(at 0 0 0)
			(layer "F.Fab")
			(effects
				(font
					(size 1.27 1.27)
				)
			)
		)
		(duplicate_pad_numbers_are_jumpers no)
		(fp_line
			(start -0.7874 -0.4064)
			(end 0.7874 -0.4064)
			(stroke
				(width 0.1524)
				(type default)
			)
			(layer "F.SilkS")
		)
		(fp_line
			(start -0.7874 0.4064)
			(end -0.7874 -0.4064)
			(stroke
				(width 0.1524)
				(type default)
			)
			(layer "F.SilkS")
		)
		(fp_line
			(start 0.7874 -0.4064)
			(end 0.7874 0.4064)
			(stroke
				(width 0.1524)
				(type default)
			)
			(layer "F.SilkS")
		)
		(fp_line
			(start 0.7874 0.4064)
			(end -0.7874 0.4064)
			(stroke
				(width 0.1524)
				(type default)
			)
			(layer "F.SilkS")
		)
		(fp_line
			(start -0.6858 -0.3048)
			(end -0.1016 -0.3048)
			(stroke
				(width 0.1)
				(type default)
			)
			(layer "F.Fab")
		)
		(fp_line
			(start -0.6858 0.3048)
			(end -0.6858 -0.3048)
			(stroke
				(width 0.1)
				(type default)
			)
			(layer "F.Fab")
		)
		(fp_line
			(start -0.1016 -0.3048)
			(end -0.1016 -0.2794)
			(stroke
				(width 0.1)
				(type default)
			)
			(layer "F.Fab")
		)
		(fp_line
			(start -0.1016 -0.2794)
			(end 0.1016 -0.2794)
			(stroke
				(width 0.1)
				(type default)
			)
			(layer "F.Fab")
		)
		(fp_line
			(start -0.1016 0.2794)
			(end -0.1016 0.3048)
			(stroke
				(width 0.1)
				(type default)
			)
			(layer "F.Fab")
		)
		(fp_line
			(start -0.1016 0.3048)
			(end -0.6858 0.3048)
			(stroke
				(width 0.1)
				(type default)
			)
			(layer "F.Fab")
		)
		(fp_line
			(start 0.1016 -0.3048)
			(end 0.6858 -0.3048)
			(stroke
				(width 0.1)
				(type default)
			)
			(layer "F.Fab")
		)
		(fp_line
			(start 0.1016 -0.2794)
			(end 0.1016 -0.3048)
			(stroke
				(width 0.1)
				(type default)
			)
			(layer "F.Fab")
		)
		(fp_line
			(start 0.1016 0.2794)
			(end -0.1016 0.2794)
			(stroke
				(width 0.1)
				(type default)
			)
			(layer "F.Fab")
		)
		(fp_line
			(start 0.1016 0.3048)
			(end 0.1016 0.2794)
			(stroke
				(width 0.1)
				(type default)
			)
			(layer "F.Fab")
		)
		(fp_line
			(start 0.6858 -0.3048)
			(end 0.6858 0.3048)
			(stroke
				(width 0.1)
				(type default)
			)
			(layer "F.Fab")
		)
		(fp_line
			(start 0.6858 0.3048)
			(end 0.1016 0.3048)
			(stroke
				(width 0.1)
				(type default)
			)
			(layer "F.Fab")
		)
		(pad "1" smd rect
			(at -0.40005 0 180)
			(size 0.4572 0.508)
			(layers "F.Cu" "F.Mask" "F.Paste")
			(net "GND")
		)
		(pad "2" smd rect
			(at 0.40005 0 180)
			(size 0.4572 0.508)
			(layers "F.Cu" "F.Mask" "F.Paste")
			(net "P12V_LED_FAN7")
		)
	)
)
